(kicad_pcb
	(version 20260206)
	(generator "pcbnew")
	(generator_version "10.0")
	(general
		(thickness 1.6)
		(legacy_teardrops no)
	)
	(paper "A4")
	(title_block
		(title "01162023_DA0F0TEBIF0_F0T_Expander_BD_F_brd_V02_OCP.brd")
		(comment 1 "Grand Teton / footprints 6239-6245 of 9728")
	)
	(layers
		(0 "F.Cu" signal "TOP")
		(4 "In1.Cu" signal "GND")
		(6 "In2.Cu" signal "VCC")
		(8 "In3.Cu" signal "VCC1")
		(10 "In4.Cu" signal "GND1")
		(12 "In5.Cu" signal "IN1")
		(14 "In6.Cu" signal "GND2")
		(16 "In7.Cu" signal "IN2")
		(18 "In8.Cu" signal "GND3")
		(20 "In9.Cu" signal "IN3")
		(22 "In10.Cu" signal "GND4")
		(24 "In11.Cu" signal "IN4")
		(26 "In12.Cu" signal "GND5")
		(28 "In13.Cu" signal "IN5")
		(30 "In14.Cu" signal "GND6")
		(32 "In15.Cu" signal "IN6")
		(34 "In16.Cu" signal "GND7")
		(2 "B.Cu" signal "BOTTOM")
		(9 "F.Adhes" user "F.Adhesive")
		(11 "B.Adhes" user "B.Adhesive")
		(13 "F.Paste" user "Package Geometry/Pastemask Top")
		(15 "B.Paste" user "Package Geometry/Pastemask Bottom")
		(5 "F.SilkS" user "Ref Des/Silkscreen Top")
		(7 "B.SilkS" user "Ref Des/Silkscreen Bottom")
		(1 "F.Mask" user "Board Geometry/Soldermask Top")
		(3 "B.Mask" user "Board Geometry/Soldermask Bottom")
		(17 "Dwgs.User" user "User.Drawings")
		(19 "Cmts.User" user "User.Comments")
		(21 "Eco1.User" user "User.Eco1")
		(23 "Eco2.User" user "User.Eco2")
		(25 "Edge.Cuts" user "Board Geometry/Outline")
		(27 "Margin" user)
		(31 "F.CrtYd" user "Package Geometry/Place Bound Top")
		(29 "B.CrtYd" user "Package Geometry/Place Bound Bottom")
		(35 "F.Fab" user "Ref Des/Assembly Top")
		(33 "B.Fab" user "Ref Des/Assembly Bottom")
	)
	(footprint ""
		(layer "F.Cu")
		(at 119.457978 -27.006296 -90)
		(property "Reference" "PR7107"
			(at 0 0 270)
			(layer "F.SilkS")
			(hide yes)
			(effects
				(font
					(size 1.27 1.27)
				)
			)
		)
		(property "Value" ""
			(at 0 0 270)
			(layer "F.Fab")
			(effects
				(font
					(size 1.27 1.27)
				)
			)
		)
		(duplicate_pad_numbers_are_jumpers no)
		(fp_line
			(start -0.7874 0.4064)
			(end -0.7874 -0.4064)
			(stroke
				(width 0.1524)
				(type default)
			)
			(layer "F.SilkS")
		)
		(fp_line
			(start 0.7874 0.4064)
			(end -0.7874 0.4064)
			(stroke
				(width 0.1524)
				(type default)
			)
			(layer "F.SilkS")
		)
		(fp_line
			(start -0.7874 -0.4064)
			(end 0.7874 -0.4064)
			(stroke
				(width 0.1524)
				(type default)
			)
			(layer "F.SilkS")
		)
		(fp_line
			(start 0.7874 -0.4064)
			(end 0.7874 0.4064)
			(stroke
				(width 0.1524)
				(type default)
			)
			(layer "F.SilkS")
		)
		(fp_line
			(start -0.67945 0.3048)
			(end -0.67945 -0.305054)
			(stroke
				(width 0.1)
				(type default)
			)
			(layer "F.Fab")
		)
		(fp_line
			(start -0.12065 0.3048)
			(end -0.67945 0.3048)
			(stroke
				(width 0.1)
				(type default)
			)
			(layer "F.Fab")
		)
		(fp_line
			(start 0.120396 0.3048)
			(end 0.120396 0.2794)
			(stroke
				(width 0.1)
				(type default)
			)
			(layer "F.Fab")
		)
		(fp_line
			(start 0.67945 0.3048)
			(end 0.120396 0.3048)
			(stroke
				(width 0.1)
				(type default)
			)
			(layer "F.Fab")
		)
		(fp_line
			(start -0.12065 0.2794)
			(end -0.12065 0.3048)
			(stroke
				(width 0.1)
				(type default)
			)
			(layer "F.Fab")
		)
		(fp_line
			(start 0.120396 0.2794)
			(end -0.12065 0.2794)
			(stroke
				(width 0.1)
				(type default)
			)
			(layer "F.Fab")
		)
		(fp_line
			(start -0.12065 -0.2794)
			(end 0.12065 -0.2794)
			(stroke
				(width 0.1)
				(type default)
			)
			(layer "F.Fab")
		)
		(fp_line
			(start 0.12065 -0.2794)
			(end 0.12065 -0.3048)
			(stroke
				(width 0.1)
				(type default)
			)
			(layer "F.Fab")
		)
		(fp_line
			(start 0.12065 -0.3048)
			(end 0.67945 -0.3048)
			(stroke
				(width 0.1)
				(type default)
			)
			(layer "F.Fab")
		)
		(fp_line
			(start 0.67945 -0.3048)
			(end 0.67945 0.3048)
			(stroke
				(width 0.1)
				(type default)
			)
			(layer "F.Fab")
		)
		(fp_line
			(start -0.67945 -0.305054)
			(end -0.12065 -0.305054)
			(stroke
				(width 0.1)
				(type default)
			)
			(layer "F.Fab")
		)
		(fp_line
			(start -0.12065 -0.305054)
			(end -0.12065 -0.2794)
			(stroke
				(width 0.1)
				(type default)
			)
			(layer "F.Fab")
		)
		(pad "1" smd circle
			(at -0.40005 0 270)
			(size 0 0)
			(layers "F.Cu" "F.Mask" "F.Paste")
			(net "P3V3_SSD4_CO_MODE")
		)
		(pad "2" smd circle
			(at 0.40005 0 270)
			(size 0 0)
			(layers "F.Cu" "F.Mask" "F.Paste")
			(net "GND")
		)
	)
	(footprint ""
		(layer "F.Cu")
		(at 336.042 -142.875)
		(property "Reference" "R4790"
			(at 0 0 0)
			(layer "F.SilkS")
			(hide yes)
			(effects
				(font
					(size 1.27 1.27)
				)
			)
		)
		(property "Value" ""
			(at 0 0 0)
			(layer "F.Fab")
			(effects
				(font
					(size 1.27 1.27)
				)
			)
		)
		(duplicate_pad_numbers_are_jumpers no)
		(fp_line
			(start -0.7874 -0.4064)
			(end 0.7874 -0.4064)
			(stroke
				(width 0.1524)
				(type default)
			)
			(layer "F.SilkS")
		)
		(fp_line
			(start -0.7874 0.4064)
			(end -0.7874 -0.4064)
			(stroke
				(width 0.1524)
				(type default)
			)
			(layer "F.SilkS")
		)
		(fp_line
			(start 0.7874 -0.4064)
			(end 0.7874 0.4064)
			(stroke
				(width 0.1524)
				(type default)
			)
			(layer "F.SilkS")
		)
		(fp_line
			(start 0.7874 0.4064)
			(end -0.7874 0.4064)
			(stroke
				(width 0.1524)
				(type default)
			)
			(layer "F.SilkS")
		)
		(fp_line
			(start -0.67945 -0.305054)
			(end -0.12065 -0.305054)
			(stroke
				(width 0.1)
				(type default)
			)
			(layer "F.Fab")
		)
		(fp_line
			(start -0.67945 0.3048)
			(end -0.67945 -0.305054)
			(stroke
				(width 0.1)
				(type default)
			)
			(layer "F.Fab")
		)
		(fp_line
			(start -0.12065 -0.305054)
			(end -0.12065 -0.2794)
			(stroke
				(width 0.1)
				(type default)
			)
			(layer "F.Fab")
		)
		(fp_line
			(start -0.12065 -0.2794)
			(end 0.12065 -0.2794)
			(stroke
				(width 0.1)
				(type default)
			)
			(layer "F.Fab")
		)
		(fp_line
			(start -0.12065 0.2794)
			(end -0.12065 0.3048)
			(stroke
				(width 0.1)
				(type default)
			)
			(layer "F.Fab")
		)
		(fp_line
			(start -0.12065 0.3048)
			(end -0.67945 0.3048)
			(stroke
				(width 0.1)
				(type default)
			)
			(layer "F.Fab")
		)
		(fp_line
			(start 0.120396 0.2794)
			(end -0.12065 0.2794)
			(stroke
				(width 0.1)
				(type default)
			)
			(layer "F.Fab")
		)
		(fp_line
			(start 0.120396 0.3048)
			(end 0.120396 0.2794)
			(stroke
				(width 0.1)
				(type default)
			)
			(layer "F.Fab")
		)
		(fp_line
			(start 0.12065 -0.3048)
			(end 0.67945 -0.3048)
			(stroke
				(width 0.1)
				(type default)
			)
			(layer "F.Fab")
		)
		(fp_line
			(start 0.12065 -0.2794)
			(end 0.12065 -0.3048)
			(stroke
				(width 0.1)
				(type default)
			)
			(layer "F.Fab")
		)
		(fp_line
			(start 0.67945 -0.3048)
			(end 0.67945 0.3048)
			(stroke
				(width 0.1)
				(type default)
			)
			(layer "F.Fab")
		)
		(fp_line
			(start 0.67945 0.3048)
			(end 0.120396 0.3048)
			(stroke
				(width 0.1)
				(type default)
			)
			(layer "F.Fab")
		)
		(pad "1" smd circle
			(at -0.40005 0)
			(size 0 0)
			(layers "F.Cu" "F.Mask" "F.Paste")
			(net "P3V3_AUX")
		)
		(pad "2" smd circle
			(at 0.40005 0)
			(size 0 0)
			(layers "F.Cu" "F.Mask" "F.Paste")
			(net "SSD15_PEX_PWR_EN_R")
		)
	)
	(footprint ""
		(layer "F.Cu")
		(at 449.179188 -415.621216 90)
		(property "Reference" "R5600"
			(at 0 0 90)
			(layer "F.SilkS")
			(hide yes)
			(effects
				(font
					(size 1.27 1.27)
				)
			)
		)
		(property "Value" ""
			(at 0 0 90)
			(layer "F.Fab")
			(effects
				(font
					(size 1.27 1.27)
				)
			)
		)
		(duplicate_pad_numbers_are_jumpers no)
		(fp_line
			(start 0.7874 -0.4064)
			(end 0.7874 0.4064)
			(stroke
				(width 0.1524)
				(type default)
			)
			(layer "F.SilkS")
		)
		(fp_line
			(start -0.7874 -0.4064)
			(end 0.7874 -0.4064)
			(stroke
				(width 0.1524)
				(type default)
			)
			(layer "F.SilkS")
		)
		(fp_line
			(start 0.7874 0.4064)
			(end -0.7874 0.4064)
			(stroke
				(width 0.1524)
				(type default)
			)
			(layer "F.SilkS")
		)
		(fp_line
			(start -0.7874 0.4064)
			(end -0.7874 -0.4064)
			(stroke
				(width 0.1524)
				(type default)
			)
			(layer "F.SilkS")
		)
		(fp_line
			(start -0.12065 -0.305054)
			(end -0.12065 -0.2794)
			(stroke
				(width 0.1)
				(type default)
			)
			(layer "F.Fab")
		)
		(fp_line
			(start -0.67945 -0.305054)
			(end -0.12065 -0.305054)
			(stroke
				(width 0.1)
				(type default)
			)
			(layer "F.Fab")
		)
		(fp_line
			(start 0.67945 -0.3048)
			(end 0.67945 0.3048)
			(stroke
				(width 0.1)
				(type default)
			)
			(layer "F.Fab")
		)
		(fp_line
			(start 0.12065 -0.3048)
			(end 0.67945 -0.3048)
			(stroke
				(width 0.1)
				(type default)
			)
			(layer "F.Fab")
		)
		(fp_line
			(start 0.12065 -0.2794)
			(end 0.12065 -0.3048)
			(stroke
				(width 0.1)
				(type default)
			)
			(layer "F.Fab")
		)
		(fp_line
			(start -0.12065 -0.2794)
			(end 0.12065 -0.2794)
			(stroke
				(width 0.1)
				(type default)
			)
			(layer "F.Fab")
		)
		(fp_line
			(start 0.120396 0.2794)
			(end -0.12065 0.2794)
			(stroke
				(width 0.1)
				(type default)
			)
			(layer "F.Fab")
		)
		(fp_line
			(start -0.12065 0.2794)
			(end -0.12065 0.3048)
			(stroke
				(width 0.1)
				(type default)
			)
			(layer "F.Fab")
		)
		(fp_line
			(start 0.67945 0.3048)
			(end 0.120396 0.3048)
			(stroke
				(width 0.1)
				(type default)
			)
			(layer "F.Fab")
		)
		(fp_line
			(start 0.120396 0.3048)
			(end 0.120396 0.2794)
			(stroke
				(width 0.1)
				(type default)
			)
			(layer "F.Fab")
		)
		(fp_line
			(start -0.12065 0.3048)
			(end -0.67945 0.3048)
			(stroke
				(width 0.1)
				(type default)
			)
			(layer "F.Fab")
		)
		(fp_line
			(start -0.67945 0.3048)
			(end -0.67945 -0.305054)
			(stroke
				(width 0.1)
				(type default)
			)
			(layer "F.Fab")
		)
		(pad "1" smd circle
			(at -0.40005 0 90)
			(size 0 0)
			(layers "F.Cu" "F.Mask" "F.Paste")
			(net "LM75_1_A1")
		)
		(pad "2" smd circle
			(at 0.40005 0 90)
			(size 0 0)
			(layers "F.Cu" "F.Mask" "F.Paste")
			(net "P3V3_AUX")
		)
	)
	(footprint ""
		(layer "F.Cu")
		(at 130.490468 -350.098614 90)
		(property "Reference" "C2271"
			(at 0 0 90)
			(layer "F.SilkS")
			(hide yes)
			(effects
				(font
					(size 1.27 1.27)
				)
			)
		)
		(property "Value" ""
			(at 0 0 90)
			(layer "F.Fab")
			(effects
				(font
					(size 1.27 1.27)
				)
			)
		)
		(duplicate_pad_numbers_are_jumpers no)
		(fp_line
			(start 0.299974 -0.150114)
			(end 0.299974 0.150114)
			(stroke
				(width 0.1)
				(type default)
			)
			(layer "F.Fab")
		)
		(fp_line
			(start -0.299974 -0.150114)
			(end 0.299974 -0.150114)
			(stroke
				(width 0.1)
				(type default)
			)
			(layer "F.Fab")
		)
		(fp_line
			(start 0.299974 0.150114)
			(end -0.299974 0.150114)
			(stroke
				(width 0.1)
				(type default)
			)
			(layer "F.Fab")
		)
		(fp_line
			(start -0.299974 0.150114)
			(end -0.299974 -0.150114)
			(stroke
				(width 0.1)
				(type default)
			)
			(layer "F.Fab")
		)
		(pad "1" smd rect
			(at -0.2667 0 90)
			(size 0.3048 0.381)
			(layers "F.Cu" "F.Mask" "F.Paste")
			(net "P5E_PEX1_STN5_TX_DP<81>")
		)
		(pad "2" smd rect
			(at 0.2667 0 90)
			(size 0.3048 0.381)
			(layers "F.Cu" "F.Mask" "F.Paste")
			(net "P5E_PEX1_STN5_TX_C_DP<81>")
		)
	)
	(footprint ""
		(layer "F.Cu")
		(at 23.128478 -260.807708 90)
		(property "Reference" "R5727"
			(at 0 0 90)
			(layer "F.SilkS")
			(hide yes)
			(effects
				(font
					(size 1.27 1.27)
				)
			)
		)
		(property "Value" ""
			(at 0 0 90)
			(layer "F.Fab")
			(effects
				(font
					(size 1.27 1.27)
				)
			)
		)
		(duplicate_pad_numbers_are_jumpers no)
		(fp_line
			(start 0.7874 -0.4064)
			(end 0.7874 0.4064)
			(stroke
				(width 0.1524)
				(type default)
			)
			(layer "F.SilkS")
		)
		(fp_line
			(start -0.7874 -0.4064)
			(end 0.7874 -0.4064)
			(stroke
				(width 0.1524)
				(type default)
			)
			(layer "F.SilkS")
		)
		(fp_line
			(start 0.7874 0.4064)
			(end -0.7874 0.4064)
			(stroke
				(width 0.1524)
				(type default)
			)
			(layer "F.SilkS")
		)
		(fp_line
			(start -0.7874 0.4064)
			(end -0.7874 -0.4064)
			(stroke
				(width 0.1524)
				(type default)
			)
			(layer "F.SilkS")
		)
		(fp_line
			(start -0.12065 -0.305054)
			(end -0.12065 -0.2794)
			(stroke
				(width 0.1)
				(type default)
			)
			(layer "F.Fab")
		)
		(fp_line
			(start -0.67945 -0.305054)
			(end -0.12065 -0.305054)
			(stroke
				(width 0.1)
				(type default)
			)
			(layer "F.Fab")
		)
		(fp_line
			(start 0.67945 -0.3048)
			(end 0.67945 0.3048)
			(stroke
				(width 0.1)
				(type default)
			)
			(layer "F.Fab")
		)
		(fp_line
			(start 0.12065 -0.3048)
			(end 0.67945 -0.3048)
			(stroke
				(width 0.1)
				(type default)
			)
			(layer "F.Fab")
		)
		(fp_line
			(start 0.12065 -0.2794)
			(end 0.12065 -0.3048)
			(stroke
				(width 0.1)
				(type default)
			)
			(layer "F.Fab")
		)
		(fp_line
			(start -0.12065 -0.2794)
			(end 0.12065 -0.2794)
			(stroke
				(width 0.1)
				(type default)
			)
			(layer "F.Fab")
		)
		(fp_line
			(start 0.120396 0.2794)
			(end -0.12065 0.2794)
			(stroke
				(width 0.1)
				(type default)
			)
			(layer "F.Fab")
		)
		(fp_line
			(start -0.12065 0.2794)
			(end -0.12065 0.3048)
			(stroke
				(width 0.1)
				(type default)
			)
			(layer "F.Fab")
		)
		(fp_line
			(start 0.67945 0.3048)
			(end 0.120396 0.3048)
			(stroke
				(width 0.1)
				(type default)
			)
			(layer "F.Fab")
		)
		(fp_line
			(start 0.120396 0.3048)
			(end 0.120396 0.2794)
			(stroke
				(width 0.1)
				(type default)
			)
			(layer "F.Fab")
		)
		(fp_line
			(start -0.12065 0.3048)
			(end -0.67945 0.3048)
			(stroke
				(width 0.1)
				(type default)
			)
			(layer "F.Fab")
		)
		(fp_line
			(start -0.67945 0.3048)
			(end -0.67945 -0.305054)
			(stroke
				(width 0.1)
				(type default)
			)
			(layer "F.Fab")
		)
		(pad "1" smd circle
			(at -0.40005 0 90)
			(size 0 0)
			(layers "F.Cu" "F.Mask" "F.Paste")
			(net "PEX0_SYS_ERR_N_G")
		)
		(pad "2" smd circle
			(at 0.40005 0 90)
			(size 0 0)
			(layers "F.Cu" "F.Mask" "F.Paste")
			(net "PEX0_SYS_ERR_FPGA")
		)
	)
	(footprint ""
		(layer "F.Cu")
		(at 131.89839 -184.656984 -90)
		(property "Reference" "R1115"
			(at 0 0 270)
			(layer "F.SilkS")
			(hide yes)
			(effects
				(font
					(size 1.27 1.27)
				)
			)
		)
		(property "Value" ""
			(at 0 0 270)
			(layer "F.Fab")
			(effects
				(font
					(size 1.27 1.27)
				)
			)
		)
		(duplicate_pad_numbers_are_jumpers no)
		(fp_line
			(start 0.7874 0.4064)
			(end -0.7874 0.4064)
			(stroke
				(width 0.1524)
				(type default)
			)
			(layer "F.SilkS")
		)
		(fp_line
			(start -0.67945 0.3048)
			(end -0.67945 -0.305054)
			(stroke
				(width 0.1)
				(type default)
			)
			(layer "F.Fab")
		)
		(fp_line
			(start -0.12065 0.3048)
			(end -0.67945 0.3048)
			(stroke
				(width 0.1)
				(type default)
			)
			(layer "F.Fab")
		)
		(fp_line
			(start 0.120396 0.3048)
			(end 0.120396 0.2794)
			(stroke
				(width 0.1)
				(type default)
			)
			(layer "F.Fab")
		)
		(fp_line
			(start 0.67945 0.3048)
			(end 0.120396 0.3048)
			(stroke
				(width 0.1)
				(type default)
			)
			(layer "F.Fab")
		)
		(fp_line
			(start -0.12065 0.2794)
			(end -0.12065 0.3048)
			(stroke
				(width 0.1)
				(type default)
			)
			(layer "F.Fab")
		)
		(fp_line
			(start 0.120396 0.2794)
			(end -0.12065 0.2794)
			(stroke
				(width 0.1)
				(type default)
			)
			(layer "F.Fab")
		)
		(fp_line
			(start -0.12065 -0.2794)
			(end 0.12065 -0.2794)
			(stroke
				(width 0.1)
				(type default)
			)
			(layer "F.Fab")
		)
		(fp_line
			(start 0.12065 -0.2794)
			(end 0.12065 -0.3048)
			(stroke
				(width 0.1)
				(type default)
			)
			(layer "F.Fab")
		)
		(fp_line
			(start 0.12065 -0.3048)
			(end 0.67945 -0.3048)
			(stroke
				(width 0.1)
				(type default)
			)
			(layer "F.Fab")
		)
		(fp_line
			(start 0.67945 -0.3048)
			(end 0.67945 0.3048)
			(stroke
				(width 0.1)
				(type default)
			)
			(layer "F.Fab")
		)
		(fp_line
			(start -0.67945 -0.305054)
			(end -0.12065 -0.305054)
			(stroke
				(width 0.1)
				(type default)
			)
			(layer "F.Fab")
		)
		(fp_line
			(start -0.12065 -0.305054)
			(end -0.12065 -0.2794)
			(stroke
				(width 0.1)
				(type default)
			)
			(layer "F.Fab")
		)
		(pad "1" smd circle
			(at -0.40005 0 270)
			(size 0 0)
			(layers "F.Cu" "F.Mask" "F.Paste")
			(net "CLK_100M_DB2000QL_GPU_REF1_R_DN")
		)
		(pad "2" smd circle
			(at 0.40005 0 270)
			(size 0 0)
			(layers "F.Cu" "F.Mask" "F.Paste")
			(net "CLK_100M_DB2000QL_GPU_REF1_DN")
		)
	)
	(footprint ""
		(layer "F.Cu")
		(at 191.817498 -402.672296 90)
		(property "Reference" "R6825"
			(at 0 0 90)
			(layer "F.SilkS")
			(hide yes)
			(effects
				(font
					(size 1.27 1.27)
				)
			)
		)
		(property "Value" ""
			(at 0 0 90)
			(layer "F.Fab")
			(effects
				(font
					(size 1.27 1.27)
				)
			)
		)
		(duplicate_pad_numbers_are_jumpers no)
		(fp_line
			(start 0.7874 -0.4064)
			(end 0.7874 0.4064)
			(stroke
				(width 0.1524)
				(type default)
			)
			(layer "F.SilkS")
		)
		(fp_line
			(start -0.7874 -0.4064)
			(end 0.7874 -0.4064)
			(stroke
				(width 0.1524)
				(type default)
			)
			(layer "F.SilkS")
		)
		(fp_line
			(start 0.7874 0.4064)
			(end -0.7874 0.4064)
			(stroke
				(width 0.1524)
				(type default)
			)
			(layer "F.SilkS")
		)
		(fp_line
			(start -0.7874 0.4064)
			(end -0.7874 -0.4064)
			(stroke
				(width 0.1524)
				(type default)
			)
			(layer "F.SilkS")
		)
		(fp_line
			(start -0.12065 -0.305054)
			(end -0.12065 -0.2794)
			(stroke
				(width 0.1)
				(type default)
			)
			(layer "F.Fab")
		)
		(fp_line
			(start -0.67945 -0.305054)
			(end -0.12065 -0.305054)
			(stroke
				(width 0.1)
				(type default)
			)
			(layer "F.Fab")
		)
		(fp_line
			(start 0.67945 -0.3048)
			(end 0.67945 0.3048)
			(stroke
				(width 0.1)
				(type default)
			)
			(layer "F.Fab")
		)
		(fp_line
			(start 0.12065 -0.3048)
			(end 0.67945 -0.3048)
			(stroke
				(width 0.1)
				(type default)
			)
			(layer "F.Fab")
		)
		(fp_line
			(start 0.12065 -0.2794)
			(end 0.12065 -0.3048)
			(stroke
				(width 0.1)
				(type default)
			)
			(layer "F.Fab")
		)
		(fp_line
			(start -0.12065 -0.2794)
			(end 0.12065 -0.2794)
			(stroke
				(width 0.1)
				(type default)
			)
			(layer "F.Fab")
		)
		(fp_line
			(start 0.120396 0.2794)
			(end -0.12065 0.2794)
			(stroke
				(width 0.1)
				(type default)
			)
			(layer "F.Fab")
		)
		(fp_line
			(start -0.12065 0.2794)
			(end -0.12065 0.3048)
			(stroke
				(width 0.1)
				(type default)
			)
			(layer "F.Fab")
		)
		(fp_line
			(start 0.67945 0.3048)
			(end 0.120396 0.3048)
			(stroke
				(width 0.1)
				(type default)
			)
			(layer "F.Fab")
		)
		(fp_line
			(start 0.120396 0.3048)
			(end 0.120396 0.2794)
			(stroke
				(width 0.1)
				(type default)
			)
			(layer "F.Fab")
		)
		(fp_line
			(start -0.12065 0.3048)
			(end -0.67945 0.3048)
			(stroke
				(width 0.1)
				(type default)
			)
			(layer "F.Fab")
		)
		(fp_line
			(start -0.67945 0.3048)
			(end -0.67945 -0.305054)
			(stroke
				(width 0.1)
				(type default)
			)
			(layer "F.Fab")
		)
		(pad "1" smd circle
			(at -0.40005 0 90)
			(size 0 0)
			(layers "F.Cu" "F.Mask" "F.Paste")
			(net "P12V_AUX")
		)
		(pad "2" smd circle
			(at 0.40005 0 90)
			(size 0 0)
			(layers "F.Cu" "F.Mask" "F.Paste")
			(net "FM_UV_LT6700_VS")
		)
	)
)
